FILE_TYPE = CONNECTIVITY;
{Allegro Design Entry HDL 17.4-2019 S026 (4007227) 1/17/2022}
"PAGE_NUMBER" = 467;
0"NC";
1"GND\g";
2"GND\g";
3"P1V8_AUX\g";
4"RT_BOARD_ID_ID0";
5"RT_BOARD_ID_ID1";
%"UNIVERSAL_GND"
"1","(-6075,3775)","0","pure_quanta_power","I1";
;
CDS_LIB"pure_quanta_power"
BOM_COST"OCP3.0 "
HDL_POWER"GND";
"A"1;
%"UNIVERSAL_POWER"
"1","(-6075,5725)","0","pure_quanta_power","I10";
;
HDL_POWER"P1V8_AUX"
CDS_LIB"pure_quanta_power";
"A"3;
%"Q_RES"
"2","(-6075,4250)","0","pure_quanta","I2";
;
LOCATION"R6744"
$SEC"1"
CDS_SEC"1"
VALUE"1K"
TOLERANCE"1%"
PACK_TYPE"0402LF"
MATERIAL"CHIP"
WATTAGE"1/16W"
CDS_LIB"pure_quanta"
PART_NUMBER"CS21002FB06";
"A"
$PN"1"5;
"B"
$PN"2"1;
%"UNIVERSAL_GND"
"1","(-5725,3775)","0","pure_quanta_power","I3";
;
CDS_LIB"pure_quanta_power"
BOM_COST"OCP3.0 "
HDL_POWER"GND";
"A"2;
%"Q_RES"
"2","(-5725,4250)","0","pure_quanta","I4";
;
LOCATION"R6745"
$SEC"1"
CDS_SEC"1"
PACK_TYPE"0402LF"
MATERIAL"CHIP"
WATTAGE"1/16W"
TOLERANCE"1%"
VALUE"1K"
CDS_LIB"pure_quanta"
PART_NUMBER"CS21002FB06";
"A"
$PN"1"4;
"B"
$PN"2"2;
%"Q_RES"
"2","(-6075,5200)","0","pure_quanta","I5";
;
LOCATION"R6742"
$SEC"1"
CDS_SEC"1"
VALUE"1K"
TOLERANCE"1%"
WATTAGE"1/16W"
PACK_TYPE"0402LF"
MATERIAL"EMPTY"
CDS_LIB"pure_quanta"
PART_NUMBER"CS21002FB06";
"A"
$PN"1"3;
"B"
$PN"2"5;
%"Q_RES"
"2","(-5725,5200)","0","pure_quanta","I6";
;
LOCATION"R6743"
$SEC"1"
CDS_SEC"1"
VALUE"1K"
MATERIAL"EMPTY"
WATTAGE"1/16W"
TOLERANCE"1%"
PACK_TYPE"0402LF"
CDS_LIB"pure_quanta"
PART_NUMBER"CS21002FB06";
"A"
$PN"1"3;
"B"
$PN"2"4;
END.
